FILE_TYPE=LIBRARY_PARTS;
primitive 'CONN7_E82125014','CONN7_E82125014_IO','CONN7_E82125014_PIP_IO';
  pin
    'IO1':
      PIN_NUMBER='(1)';
      BIDIRECTIONAL='TRUE';
      INPUT_LOAD='(-0.01,0.01)';
      OUTPUT_LOAD='(1.0,-1.0)';
    'IO2':
      PIN_NUMBER='(2)';
      BIDIRECTIONAL='TRUE';
      INPUT_LOAD='(-0.01,0.01)';
      OUTPUT_LOAD='(1.0,-1.0)';
    'IO3':
      PIN_NUMBER='(3)';
      BIDIRECTIONAL='TRUE';
      INPUT_LOAD='(-0.01,0.01)';
      OUTPUT_LOAD='(1.0,-1.0)';
    'IO4':
      PIN_NUMBER='(4)';
      BIDIRECTIONAL='TRUE';
      INPUT_LOAD='(-0.01,0.01)';
      OUTPUT_LOAD='(1.0,-1.0)';
    'IO5':
      PIN_NUMBER='(5)';
      BIDIRECTIONAL='TRUE';
      INPUT_LOAD='(-0.01,0.01)';
      OUTPUT_LOAD='(1.0,-1.0)';
    'IO6':
      PIN_NUMBER='(6)';
      BIDIRECTIONAL='TRUE';
      INPUT_LOAD='(-0.01,0.01)';
      OUTPUT_LOAD='(1.0,-1.0)';
    'IO7':
      PIN_NUMBER='(7)';
      BIDIRECTIONAL='TRUE';
      INPUT_LOAD='(-0.01,0.01)';
      OUTPUT_LOAD='(1.0,-1.0)';
    'MH1':
      PIN_NUMBER='(MH1)';
      PINUSE='GROUND';
      NO_LOAD_CHECK='Both';
      NO_IO_CHECK='Both';
      NO_ASSERT_CHECK='TRUE';
      NO_DIR_CHECK='TRUE';
      ALLOW_CONNECT='TRUE';
    'MH2':
      PIN_NUMBER='(MH2)';
      PINUSE='GROUND';
      NO_LOAD_CHECK='Both';
      NO_IO_CHECK='Both';
      NO_ASSERT_CHECK='TRUE';
      NO_DIR_CHECK='TRUE';
      ALLOW_CONNECT='TRUE';
  end_pin;
  body
    PART_NAME='CONN7_E82125014';
    PHYS_DES_PREFIX='J';
  end_body;
end_primitive;

primitive 'CONN7_E82125014_TH','CONN7_E82125014_PIP_TH';
  pin
    'GND'<2>:
      PIN_NUMBER='(1)';
      BIDIRECTIONAL='TRUE';
      INPUT_LOAD='(-0.01,0.01)';
      OUTPUT_LOAD='(1.0,-1.0)';
    'GND'<1>:
      PIN_NUMBER='(4)';
      BIDIRECTIONAL='TRUE';
      INPUT_LOAD='(-0.01,0.01)';
      OUTPUT_LOAD='(1.0,-1.0)';
    'GND'<0>:
      PIN_NUMBER='(7)';
      BIDIRECTIONAL='TRUE';
      INPUT_LOAD='(-0.01,0.01)';
      OUTPUT_LOAD='(1.0,-1.0)';
    'MH1':
      PIN_NUMBER='(MH1)';
      PINUSE='GROUND';
      NO_LOAD_CHECK='Both';
      NO_IO_CHECK='Both';
      NO_ASSERT_CHECK='TRUE';
      NO_DIR_CHECK='TRUE';
      ALLOW_CONNECT='TRUE';
    'MH2':
      PIN_NUMBER='(MH2)';
      PINUSE='GROUND';
      NO_LOAD_CHECK='Both';
      NO_IO_CHECK='Both';
      NO_ASSERT_CHECK='TRUE';
      NO_DIR_CHECK='TRUE';
      ALLOW_CONNECT='TRUE';
    'SATA_RXN':
      PIN_NUMBER='(5)';
      BIDIRECTIONAL='TRUE';
      INPUT_LOAD='(-0.01,0.01)';
      OUTPUT_LOAD='(1.0,-1.0)';
    'SATA_RXP':
      PIN_NUMBER='(6)';
      BIDIRECTIONAL='TRUE';
      INPUT_LOAD='(-0.01,0.01)';
      OUTPUT_LOAD='(1.0,-1.0)';
    'SATA_TXN':
      PIN_NUMBER='(3)';
      BIDIRECTIONAL='TRUE';
      INPUT_LOAD='(-0.01,0.01)';
      OUTPUT_LOAD='(1.0,-1.0)';
    'SATA_TXP':
      PIN_NUMBER='(2)';
      BIDIRECTIONAL='TRUE';
      INPUT_LOAD='(-0.01,0.01)';
      OUTPUT_LOAD='(1.0,-1.0)';
  end_pin;
  body
    PART_NAME='CONN7_E82125014';
    PHYS_DES_PREFIX='J';
  end_body;
end_primitive;

END.
